(kicad_pcb
	(version 20260206)
	(generator "pcbnew")
	(generator_version "10.0")
	(general
		(thickness 1.6)
		(legacy_teardrops no)
	)
	(paper "A4")
	(title_block
		(title "Wiwynn_Tioga_Pass_MB.brd")
		(comment 1 "Tioga Pass / footprint 153 of 4770 (U25W4), pads 212-323 of 456")
	)
	(layers
		(0 "F.Cu" signal "TOP")
		(4 "In1.Cu" signal "L2GND")
		(6 "In2.Cu" signal "L3")
		(8 "In3.Cu" signal "L4GND")
		(10 "In4.Cu" signal "L5")
		(12 "In5.Cu" signal "L6GND")
		(14 "In6.Cu" signal "L7VCC")
		(16 "In7.Cu" signal "L8VCC")
		(18 "In8.Cu" signal "L9GND")
		(20 "In9.Cu" signal "L10")
		(22 "In10.Cu" signal "L11GND")
		(24 "In11.Cu" signal "L12")
		(26 "In12.Cu" signal "L13GND")
		(2 "B.Cu" signal "BOTTOM")
		(9 "F.Adhes" user "F.Adhesive")
		(11 "B.Adhes" user "B.Adhesive")
		(13 "F.Paste" user "Package Geometry/Pastemask Top")
		(15 "B.Paste" user "Package Geometry/Pastemask Bottom")
		(5 "F.SilkS" user "Ref Des/Silkscreen Top")
		(7 "B.SilkS" user "Ref Des/Silkscreen Bottom")
		(1 "F.Mask" user "Board Geometry/Soldermask Top")
		(3 "B.Mask" user "Board Geometry/Soldermask Bottom")
		(17 "Dwgs.User" user "User.Drawings")
		(19 "Cmts.User" user "User.Comments")
		(21 "Eco1.User" user "User.Eco1")
		(23 "Eco2.User" user "User.Eco2")
		(25 "Edge.Cuts" user "Board Geometry/Outline")
		(27 "Margin" user)
		(31 "F.CrtYd" user "Package Geometry/Place Bound Top")
		(29 "B.CrtYd" user "Package Geometry/Place Bound Bottom")
		(35 "F.Fab" user "Ref Des/Assembly Top")
		(33 "B.Fab" user "Ref Des/Assembly Bottom")
	)
	(footprint ""
		(layer "F.Cu")
		(at 415.490152 -34.934652 90)
		(property "Reference" "U25W4"
			(at 0 0 90)
			(layer "F.SilkS")
			(hide yes)
			(effects
				(font
					(size 1.27 1.27)
				)
			)
		)
		(property "Value" "*"
			(at -17.0307 -8.698992 90)
			(unlocked yes)
			(layer "F.Fab")
			(hide yes)
			(effects
				(font
					(size 1.27 1.016)
					(thickness 0.1524)
				)
			)
		)
		(property "Device Type" "AST2520A1-GP-GP_ASIC2-GB1-AST2A"
			(at -17.0307 -10.222992 90)
			(unlocked yes)
			(layer "F.Fab")
			(hide yes)
			(effects
				(font
					(size 1.27 1.016)
					(thickness 0.1524)
				)
			)
		)
		(duplicate_pad_numbers_are_jumpers no)
		(pad "H22" smd circle
			(at 8.400034 -2.800096 90)
			(size 0.3556 0.3556)
			(layers "F.Cu" "F.Mask" "F.Paste")
			(net "PWRGD_SYS_PWROK")
		)
		(pad "J1" smd circle
			(at -8.400034 -1.999996 90)
			(size 0.3556 0.3556)
			(layers "F.Cu" "F.Mask" "F.Paste")
			(net "PD_ADCREXT")
		)
		(pad "J2" smd circle
			(at -7.599934 -1.999996 90)
			(size 0.3556 0.3556)
			(layers "F.Cu" "F.Mask" "F.Paste")
			(net "BMC_VGA_BLUE")
		)
		(pad "J3" smd circle
			(at -6.800088 -1.999996 90)
			(size 0.3556 0.3556)
			(layers "F.Cu" "F.Mask" "F.Paste")
			(net "BMC_VGA_GREEN")
		)
		(pad "J4" smd circle
			(at -5.999988 -1.999996 90)
			(size 0.3556 0.3556)
			(layers "F.Cu" "F.Mask" "F.Paste")
			(net "BMC_VGA_RED")
		)
		(pad "J5" smd circle
			(at -5.199888 -1.999996 90)
			(size 0.3556 0.3556)
			(layers "F.Cu" "F.Mask" "F.Paste")
			(net "GND")
		)
		(pad "J6" smd circle
			(at -4.400042 -1.999996 90)
			(size 0.3556 0.3556)
			(layers "F.Cu" "F.Mask" "F.Paste")
			(net "VCC_ADCAV3V3")
		)
		(pad "J7" smd circle
			(at -3.599942 -1.999996 90)
			(size 0.3556 0.3556)
			(layers "F.Cu" "F.Mask" "F.Paste")
			(net "VCC_VA_3V3")
		)
		(pad "J9" smd circle
			(at -1.999996 -1.999996 90)
			(size 0.3556 0.3556)
			(layers "F.Cu" "F.Mask" "F.Paste")
			(net "GND")
		)
		(pad "J10" smd circle
			(at -1.199896 -1.999996 90)
			(size 0.3556 0.3556)
			(layers "F.Cu" "F.Mask" "F.Paste")
			(net "GND")
		)
		(pad "J11" smd circle
			(at -0.40005 -1.999996 90)
			(size 0.3556 0.3556)
			(layers "F.Cu" "F.Mask" "F.Paste")
			(net "GND")
		)
		(pad "J12" smd circle
			(at 0.40005 -1.999996 90)
			(size 0.3556 0.3556)
			(layers "F.Cu" "F.Mask" "F.Paste")
			(net "GND")
		)
		(pad "J13" smd circle
			(at 1.199896 -1.999996 90)
			(size 0.3556 0.3556)
			(layers "F.Cu" "F.Mask" "F.Paste")
			(net "GND")
		)
		(pad "J14" smd circle
			(at 1.999996 -1.999996 90)
			(size 0.3556 0.3556)
			(layers "F.Cu" "F.Mask" "F.Paste")
			(net "GND")
		)
		(pad "J16" smd circle
			(at 3.599942 -1.999996 90)
			(size 0.3556 0.3556)
			(layers "F.Cu" "F.Mask" "F.Paste")
			(net "P1V15_AUX_BMC")
		)
		(pad "J17" smd circle
			(at 4.400042 -1.999996 90)
			(size 0.3556 0.3556)
			(layers "F.Cu" "F.Mask" "F.Paste")
			(net "P3V3_STBY")
		)
		(pad "J18" smd circle
			(at 5.199888 -1.999996 90)
			(size 0.3556 0.3556)
			(layers "F.Cu" "F.Mask" "F.Paste")
			(net "SPI_BMC_BT_WP0_N")
		)
		(pad "J19" smd circle
			(at 5.999988 -1.999996 90)
			(size 0.3556 0.3556)
			(layers "F.Cu" "F.Mask" "F.Paste")
			(net "IRQ_PVDDQ_ABC_VRHOT_LVT3_N")
		)
		(pad "J20" smd circle
			(at 6.800088 -1.999996 90)
			(size 0.3556 0.3556)
			(layers "F.Cu" "F.Mask" "F.Paste")
			(net "CLK_48M_USB_BMC_R")
		)
		(pad "J21" smd circle
			(at 7.599934 -1.999996 90)
			(size 0.3556 0.3556)
			(layers "F.Cu" "F.Mask" "F.Paste")
			(net "GND")
		)
		(pad "J22" smd circle
			(at 8.400034 -1.999996 90)
			(size 0.3556 0.3556)
			(layers "F.Cu" "F.Mask" "F.Paste")
			(net "GND")
		)
		(pad "K1" smd circle
			(at -8.400034 -1.199896 90)
			(size 0.3556 0.3556)
			(layers "F.Cu" "F.Mask" "F.Paste")
			(net "UART_BMC_TXD5")
		)
		(pad "K2" smd circle
			(at -7.599934 -1.199896 90)
			(size 0.3556 0.3556)
			(layers "F.Cu" "F.Mask" "F.Paste")
			(net "UART_BMC_RXD5")
		)
		(pad "K3" smd circle
			(at -6.800088 -1.199896 90)
			(size 0.3556 0.3556)
			(layers "F.Cu" "F.Mask" "F.Paste")
			(net "PD_SP_ENTEST")
		)
		(pad "K4" smd circle
			(at -5.999988 -1.199896 90)
			(size 0.3556 0.3556)
			(layers "F.Cu" "F.Mask" "F.Paste")
			(net "A_DACRSET")
		)
		(pad "K5" smd circle
			(at -5.199888 -1.199896 90)
			(size 0.3556 0.3556)
			(layers "F.Cu" "F.Mask" "F.Paste")
			(net "VCC_DACAV3V3")
		)
		(pad "K6" smd circle
			(at -4.400042 -1.199896 90)
			(size 0.3556 0.3556)
			(layers "F.Cu" "F.Mask" "F.Paste")
			(net "VCC_DACAV3V3")
		)
		(pad "K7" smd circle
			(at -3.599942 -1.199896 90)
			(size 0.3556 0.3556)
			(layers "F.Cu" "F.Mask" "F.Paste")
			(net "VCC_D_3V3")
		)
		(pad "K9" smd circle
			(at -1.999996 -1.199896 90)
			(size 0.3556 0.3556)
			(layers "F.Cu" "F.Mask" "F.Paste")
			(net "GND")
		)
		(pad "K10" smd circle
			(at -1.199896 -1.199896 90)
			(size 0.3556 0.3556)
			(layers "F.Cu" "F.Mask" "F.Paste")
			(net "GND")
		)
		(pad "K11" smd circle
			(at -0.40005 -1.199896 90)
			(size 0.3556 0.3556)
			(layers "F.Cu" "F.Mask" "F.Paste")
			(net "GND")
		)
		(pad "K12" smd circle
			(at 0.40005 -1.199896 90)
			(size 0.3556 0.3556)
			(layers "F.Cu" "F.Mask" "F.Paste")
			(net "GND")
		)
		(pad "K13" smd circle
			(at 1.199896 -1.199896 90)
			(size 0.3556 0.3556)
			(layers "F.Cu" "F.Mask" "F.Paste")
			(net "GND")
		)
		(pad "K14" smd circle
			(at 1.999996 -1.199896 90)
			(size 0.3556 0.3556)
			(layers "F.Cu" "F.Mask" "F.Paste")
			(net "GND")
		)
		(pad "K16" smd circle
			(at 3.599942 -1.199896 90)
			(size 0.3556 0.3556)
			(layers "F.Cu" "F.Mask" "F.Paste")
			(net "GND")
		)
		(pad "K17" smd circle
			(at 4.400042 -1.199896 90)
			(size 0.3556 0.3556)
			(layers "F.Cu" "F.Mask" "F.Paste")
			(net "P3V3_STBY")
		)
		(pad "K18" smd circle
			(at 5.199888 -1.199896 90)
			(size 0.3556 0.3556)
			(layers "F.Cu" "F.Mask" "F.Paste")
			(net "H_CPU0_FAST_WAKE_LVT3_N")
		)
		(pad "K19" smd circle
			(at 5.999988 -1.199896 90)
			(size 0.3556 0.3556)
			(layers "F.Cu" "F.Mask" "F.Paste")
			(net "PWRGD_PCH_PWROK")
		)
		(pad "K20" smd circle
			(at 6.800088 -1.199896 90)
			(size 0.3556 0.3556)
			(layers "F.Cu" "F.Mask" "F.Paste")
			(net "PD_PEREXT")
		)
		(pad "K21" smd circle
			(at 7.599934 -1.199896 90)
			(size 0.3556 0.3556)
			(layers "F.Cu" "F.Mask" "F.Paste")
			(net "CLK_100M_BMC_PE_R_DP")
		)
		(pad "K22" smd circle
			(at 8.400034 -1.199896 90)
			(size 0.3556 0.3556)
			(layers "F.Cu" "F.Mask" "F.Paste")
			(net "CLK_100M_BMC_PE_R_DN")
		)
		(pad "L1" smd circle
			(at -8.400034 -0.40005 90)
			(size 0.3556 0.3556)
			(layers "F.Cu" "F.Mask" "F.Paste")
			(net "SMB_VR_STBY_LVC3_SCL_R")
		)
		(pad "L2" smd circle
			(at -7.599934 -0.40005 90)
			(size 0.3556 0.3556)
			(layers "F.Cu" "F.Mask" "F.Paste")
			(net "SGPIO_BMC_LD_R_N")
		)
		(pad "L3" smd circle
			(at -6.800088 -0.40005 90)
			(size 0.3556 0.3556)
			(layers "F.Cu" "F.Mask" "F.Paste")
			(net "SMB_SMLINK0_STBY_LVC3_SCL_R")
		)
		(pad "L4" smd circle
			(at -5.999988 -0.40005 90)
			(size 0.3556 0.3556)
			(layers "F.Cu" "F.Mask" "F.Paste")
			(net "SMB_SMLINK0_STBY_LVC3_SDA_R")
		)
		(pad "L5" smd circle
			(at -5.199888 -0.40005 90)
			(size 0.3556 0.3556)
			(layers "F.Cu" "F.Mask" "F.Paste")
			(net "VCC_A_1V1")
		)
		(pad "L6" smd circle
			(at -4.400042 -0.40005 90)
			(size 0.3556 0.3556)
			(layers "F.Cu" "F.Mask" "F.Paste")
			(net "VCC_A_1V1")
		)
		(pad "L7" smd circle
			(at -3.599942 -0.40005 90)
			(size 0.3556 0.3556)
			(layers "F.Cu" "F.Mask" "F.Paste")
			(net "P1V15_AUX_BMC")
		)
		(pad "L9" smd circle
			(at -1.999996 -0.40005 90)
			(size 0.3556 0.3556)
			(layers "F.Cu" "F.Mask" "F.Paste")
			(net "GND")
		)
		(pad "L10" smd circle
			(at -1.199896 -0.40005 90)
			(size 0.3556 0.3556)
			(layers "F.Cu" "F.Mask" "F.Paste")
			(net "GND")
		)
		(pad "L11" smd circle
			(at -0.40005 -0.40005 90)
			(size 0.3556 0.3556)
			(layers "F.Cu" "F.Mask" "F.Paste")
			(net "GND")
		)
		(pad "L12" smd circle
			(at 0.40005 -0.40005 90)
			(size 0.3556 0.3556)
			(layers "F.Cu" "F.Mask" "F.Paste")
			(net "GND")
		)
		(pad "L13" smd circle
			(at 1.199896 -0.40005 90)
			(size 0.3556 0.3556)
			(layers "F.Cu" "F.Mask" "F.Paste")
			(net "GND")
		)
		(pad "L14" smd circle
			(at 1.999996 -0.40005 90)
			(size 0.3556 0.3556)
			(layers "F.Cu" "F.Mask" "F.Paste")
			(net "GND")
		)
		(pad "L16" smd circle
			(at 3.599942 -0.40005 90)
			(size 0.3556 0.3556)
			(layers "F.Cu" "F.Mask" "F.Paste")
			(net "VCC_D_3V3")
		)
		(pad "L17" smd circle
			(at 4.400042 -0.40005 90)
			(size 0.3556 0.3556)
			(layers "F.Cu" "F.Mask" "F.Paste")
			(net "P1V15_AUX_BMC")
		)
		(pad "L18" smd circle
			(at 5.199888 -0.40005 90)
			(size 0.3556 0.3556)
			(layers "F.Cu" "F.Mask" "F.Paste")
			(net "FM_MP_PS_FAIL_N")
		)
		(pad "L19" smd circle
			(at 5.999988 -0.40005 90)
			(size 0.3556 0.3556)
			(layers "F.Cu" "F.Mask" "F.Paste")
			(net "BMC_DEBUG_EN_N")
		)
		(pad "L20" smd circle
			(at 6.800088 -0.40005 90)
			(size 0.3556 0.3556)
			(layers "F.Cu" "F.Mask" "F.Paste")
			(net "RST_PLTRST_BUF_N_R")
		)
		(pad "L21" smd circle
			(at 7.599934 -0.40005 90)
			(size 0.3556 0.3556)
			(layers "F.Cu" "F.Mask" "F.Paste")
			(net "P2E_SSB_BMC_RX_DP")
		)
		(pad "L22" smd circle
			(at 8.400034 -0.40005 90)
			(size 0.3556 0.3556)
			(layers "F.Cu" "F.Mask" "F.Paste")
			(net "P2E_SSB_BMC_RX_DN")
		)
		(pad "M1" smd circle
			(at -8.400034 0.40005 90)
			(size 0.3556 0.3556)
			(layers "F.Cu" "F.Mask" "F.Paste")
			(net "GND")
		)
		(pad "M2" smd circle
			(at -7.599934 0.40005 90)
			(size 0.3556 0.3556)
			(layers "F.Cu" "F.Mask" "F.Paste")
			(net "GND")
		)
		(pad "M3" smd circle
			(at -6.800088 0.40005 90)
			(size 0.3556 0.3556)
			(layers "F.Cu" "F.Mask" "F.Paste")
			(net "GND")
		)
		(pad "M4" smd circle
			(at -5.999988 0.40005 90)
			(size 0.3556 0.3556)
			(layers "F.Cu" "F.Mask" "F.Paste")
			(net "GND")
		)
		(pad "M5" smd circle
			(at -5.199888 0.40005 90)
			(size 0.3556 0.3556)
			(layers "F.Cu" "F.Mask" "F.Paste")
			(net "GND")
		)
		(pad "M6" smd circle
			(at -4.400042 0.40005 90)
			(size 0.3556 0.3556)
			(layers "F.Cu" "F.Mask" "F.Paste")
			(net "GND")
		)
		(pad "M7" smd circle
			(at -3.599942 0.40005 90)
			(size 0.3556 0.3556)
			(layers "F.Cu" "F.Mask" "F.Paste")
			(net "GND")
		)
		(pad "M9" smd circle
			(at -1.999996 0.40005 90)
			(size 0.3556 0.3556)
			(layers "F.Cu" "F.Mask" "F.Paste")
			(net "GND")
		)
		(pad "M10" smd circle
			(at -1.199896 0.40005 90)
			(size 0.3556 0.3556)
			(layers "F.Cu" "F.Mask" "F.Paste")
			(net "GND")
		)
		(pad "M11" smd circle
			(at -0.40005 0.40005 90)
			(size 0.3556 0.3556)
			(layers "F.Cu" "F.Mask" "F.Paste")
			(net "GND")
		)
		(pad "M12" smd circle
			(at 0.40005 0.40005 90)
			(size 0.3556 0.3556)
			(layers "F.Cu" "F.Mask" "F.Paste")
			(net "GND")
		)
		(pad "M13" smd circle
			(at 1.199896 0.40005 90)
			(size 0.3556 0.3556)
			(layers "F.Cu" "F.Mask" "F.Paste")
			(net "GND")
		)
		(pad "M14" smd circle
			(at 1.999996 0.40005 90)
			(size 0.3556 0.3556)
			(layers "F.Cu" "F.Mask" "F.Paste")
			(net "GND")
		)
		(pad "M16" smd circle
			(at 3.599942 0.40005 90)
			(size 0.3556 0.3556)
			(layers "F.Cu" "F.Mask" "F.Paste")
			(net "GND")
		)
		(pad "M17" smd circle
			(at 4.400042 0.40005 90)
			(size 0.3556 0.3556)
			(layers "F.Cu" "F.Mask" "F.Paste")
			(net "GND")
		)
		(pad "M18" smd circle
			(at 5.199888 0.40005 90)
			(size 0.3556 0.3556)
			(layers "F.Cu" "F.Mask" "F.Paste")
			(net "SMB_LAN_STBY_LVC3_SCL_R")
		)
		(pad "M19" smd circle
			(at 5.999988 0.40005 90)
			(size 0.3556 0.3556)
			(layers "F.Cu" "F.Mask" "F.Paste")
			(net "SMB_LAN_STBY_LVC3_SDA_R")
		)
		(pad "M20" smd circle
			(at 6.800088 0.40005 90)
			(size 0.3556 0.3556)
			(layers "F.Cu" "F.Mask" "F.Paste")
			(net "SMB_SLOTX24_STBY_LVC3_SCL_R")
		)
		(pad "M21" smd circle
			(at 7.599934 0.40005 90)
			(size 0.3556 0.3556)
			(layers "F.Cu" "F.Mask" "F.Paste")
			(net "P2E_SSB_BMC_TX_C_DP")
		)
		(pad "M22" smd circle
			(at 8.400034 0.40005 90)
			(size 0.3556 0.3556)
			(layers "F.Cu" "F.Mask" "F.Paste")
			(net "P2E_SSB_BMC_TX_C_DN")
		)
		(pad "N1" smd circle
			(at -8.400034 1.199896 90)
			(size 0.3556 0.3556)
			(layers "F.Cu" "F.Mask" "F.Paste")
			(net "SMB_SENSOR_BMC_STBY_LVC3_SCL")
		)
		(pad "N2" smd circle
			(at -7.599934 1.199896 90)
			(size 0.3556 0.3556)
			(layers "F.Cu" "F.Mask" "F.Paste")
			(net "SMB_VR_STBY_LVC3_SDA_R")
		)
		(pad "N3" smd circle
			(at -6.800088 1.199896 90)
			(size 0.3556 0.3556)
			(layers "F.Cu" "F.Mask" "F.Paste")
			(net "SGPIO_BMC_DOUT_R")
		)
		(pad "N4" smd circle
			(at -5.999988 1.199896 90)
			(size 0.3556 0.3556)
			(layers "F.Cu" "F.Mask" "F.Paste")
			(net "SGPIO_BMC_DIN")
		)
		(pad "N5" smd circle
			(at -5.199888 1.199896 90)
			(size 0.3556 0.3556)
			(layers "F.Cu" "F.Mask" "F.Paste")
			(net "BMC_VGA_HSYNC")
		)
		(pad "N6" smd circle
			(at -4.400042 1.199896 90)
			(size 0.3556 0.3556)
			(layers "F.Cu" "F.Mask" "F.Paste")
			(net "VCC_D_3V3")
		)
		(pad "N7" smd circle
			(at -3.599942 1.199896 90)
			(size 0.3556 0.3556)
			(layers "F.Cu" "F.Mask" "F.Paste")
			(net "P1V15_AUX_BMC")
		)
		(pad "N9" smd circle
			(at -1.999996 1.199896 90)
			(size 0.3556 0.3556)
			(layers "F.Cu" "F.Mask" "F.Paste")
			(net "GND")
		)
		(pad "N10" smd circle
			(at -1.199896 1.199896 90)
			(size 0.3556 0.3556)
			(layers "F.Cu" "F.Mask" "F.Paste")
			(net "GND")
		)
		(pad "N11" smd circle
			(at -0.40005 1.199896 90)
			(size 0.3556 0.3556)
			(layers "F.Cu" "F.Mask" "F.Paste")
			(net "GND")
		)
		(pad "N12" smd circle
			(at 0.40005 1.199896 90)
			(size 0.3556 0.3556)
			(layers "F.Cu" "F.Mask" "F.Paste")
			(net "GND")
		)
		(pad "N13" smd circle
			(at 1.199896 1.199896 90)
			(size 0.3556 0.3556)
			(layers "F.Cu" "F.Mask" "F.Paste")
			(net "GND")
		)
		(pad "N14" smd circle
			(at 1.999996 1.199896 90)
			(size 0.3556 0.3556)
			(layers "F.Cu" "F.Mask" "F.Paste")
			(net "GND")
		)
		(pad "N16" smd circle
			(at 3.599942 1.199896 90)
			(size 0.3556 0.3556)
			(layers "F.Cu" "F.Mask" "F.Paste")
			(net "P1V15_AUX_BMC")
		)
		(pad "N17" smd circle
			(at 4.400042 1.199896 90)
			(size 0.3556 0.3556)
			(layers "F.Cu" "F.Mask" "F.Paste")
			(net "VCC_D_3V3")
		)
		(pad "N18" smd circle
			(at 5.199888 1.199896 90)
			(size 0.3556 0.3556)
			(layers "F.Cu" "F.Mask" "F.Paste")
			(net "IRQ_LOM_ALERT_N")
		)
		(pad "N19" smd circle
			(at 5.999988 1.199896 90)
			(size 0.3556 0.3556)
			(layers "F.Cu" "F.Mask" "F.Paste")
			(net "IRQ_HSC_FAULT_N")
		)
		(pad "N20" smd circle
			(at 6.800088 1.199896 90)
			(size 0.3556 0.3556)
			(layers "F.Cu" "F.Mask" "F.Paste")
			(net "FM_PE_BMC_WAKE_N")
		)
		(pad "N21" smd circle
			(at 7.599934 1.199896 90)
			(size 0.3556 0.3556)
			(layers "F.Cu" "F.Mask" "F.Paste")
			(net "FM_UARTSW_LSB_N")
		)
		(pad "N22" smd circle
			(at 8.400034 1.199896 90)
			(size 0.3556 0.3556)
			(layers "F.Cu" "F.Mask" "F.Paste")
			(net "FM_UARTSW_MSB_N")
		)
		(pad "P1" smd circle
			(at -8.400034 1.999996 90)
			(size 0.3556 0.3556)
			(layers "F.Cu" "F.Mask" "F.Paste")
			(net "SMB_SENSOR_BMC_STBY_LVC3_SDA")
		)
		(pad "P2" smd circle
			(at -7.599934 1.999996 90)
			(size 0.3556 0.3556)
			(layers "F.Cu" "F.Mask" "F.Paste")
			(net "SMB_BMC_PMBUS_STBY_LVC3_SCL_R")
		)
		(pad "P3" smd circle
			(at -6.800088 1.999996 90)
			(size 0.3556 0.3556)
			(layers "F.Cu" "F.Mask" "F.Paste")
			(net "FM_PMBUS_ALERT_BUF_EN_R3_N")
		)
		(pad "P4" smd circle
			(at -5.999988 1.999996 90)
			(size 0.3556 0.3556)
			(layers "F.Cu" "F.Mask" "F.Paste")
			(net "FM_MEM_THERM_EVENT_PCH_N")
		)
		(pad "P5" smd circle
			(at -5.199888 1.999996 90)
			(size 0.3556 0.3556)
			(layers "F.Cu" "F.Mask" "F.Paste")
			(net "FM_CPU1_THERMTRIP_LATCH_LVT3_N")
		)
		(pad "P6" smd circle
			(at -4.400042 1.999996 90)
			(size 0.3556 0.3556)
			(layers "F.Cu" "F.Mask" "F.Paste")
			(net "VCC_D_3V3")
		)
		(pad "P7" smd circle
			(at -3.599942 1.999996 90)
			(size 0.3556 0.3556)
			(layers "F.Cu" "F.Mask" "F.Paste")
			(net "P1V15_AUX_BMC")
		)
		(pad "P9" smd circle
			(at -1.999996 1.999996 90)
			(size 0.3556 0.3556)
			(layers "F.Cu" "F.Mask" "F.Paste")
			(net "P1V15_AUX_BMC")
		)
		(pad "P10" smd circle
			(at -1.199896 1.999996 90)
			(size 0.3556 0.3556)
			(layers "F.Cu" "F.Mask" "F.Paste")
			(net "P1V15_AUX_BMC")
		)
		(pad "P11" smd circle
			(at -0.40005 1.999996 90)
			(size 0.3556 0.3556)
			(layers "F.Cu" "F.Mask" "F.Paste")
			(net "P1V15_AUX_BMC")
		)
		(pad "P12" smd circle
			(at 0.40005 1.999996 90)
			(size 0.3556 0.3556)
			(layers "F.Cu" "F.Mask" "F.Paste")
			(net "P1V15_AUX_BMC")
		)
	)
)
